(kicad_pcb
	(version 20260206)
	(generator "pcbnew")
	(generator_version "10.0")
	(general
		(thickness 1.6)
		(legacy_teardrops no)
	)
	(paper "A4")
	(title_block
		(title "peb — Lightning_PEB_BRD.brd")
		(comment 1 "Lightning (Wiwynn / Facebook NVMe JBOF) / footprints 2410-2416 of 2563")
	)
	(layers
		(0 "F.Cu" signal "TOP")
		(4 "In1.Cu" signal "L2GND")
		(6 "In2.Cu" signal "L3")
		(8 "In3.Cu" signal "L4VCC")
		(10 "In4.Cu" signal "L5VCC")
		(12 "In5.Cu" signal "L6")
		(14 "In6.Cu" signal "L7GND")
		(2 "B.Cu" signal "BOTTOM")
		(9 "F.Adhes" user "F.Adhesive")
		(11 "B.Adhes" user "B.Adhesive")
		(13 "F.Paste" user "Package Geometry/Pastemask Top")
		(15 "B.Paste" user "Package Geometry/Pastemask Bottom")
		(5 "F.SilkS" user "Ref Des/Silkscreen Top")
		(7 "B.SilkS" user "Ref Des/Silkscreen Bottom")
		(1 "F.Mask" user "Board Geometry/Soldermask Top")
		(3 "B.Mask" user "Board Geometry/Soldermask Bottom")
		(17 "Dwgs.User" user "User.Drawings")
		(19 "Cmts.User" user "User.Comments")
		(21 "Eco1.User" user "User.Eco1")
		(23 "Eco2.User" user "User.Eco2")
		(25 "Edge.Cuts" user "Board Geometry/Outline")
		(27 "Margin" user)
		(31 "F.CrtYd" user "Package Geometry/Place Bound Top")
		(29 "B.CrtYd" user "Package Geometry/Place Bound Bottom")
		(35 "F.Fab" user "Ref Des/Assembly Top")
		(33 "B.Fab" user "Ref Des/Assembly Bottom")
	)
	(footprint ""
		(layer "B.Cu")
		(at 61.341 -121.412 -90)
		(property "Reference" "R598"
			(at 0 0 90)
			(layer "B.SilkS")
			(hide yes)
			(effects
				(font
					(size 1.27 1.27)
				)
				(justify mirror)
			)
		)
		(property "Value" "4K7R2F-GP"
			(at -0.064008 -3.993896 270)
			(unlocked yes)
			(layer "B.Fab")
			(hide yes)
			(effects
				(font
					(size 1.016 1.016)
					(thickness 0.1524)
				)
				(justify mirror)
			)
		)
		(property "Device Type" "R402H16"
			(at -0.064008 -5.517896 270)
			(unlocked yes)
			(layer "B.Fab")
			(hide yes)
			(effects
				(font
					(size 1.016 1.016)
					(thickness 0.1524)
				)
				(justify mirror)
			)
		)
		(duplicate_pad_numbers_are_jumpers no)
		(fp_line
			(start -0.508 -0.9398)
			(end 0.508 -0.9398)
			(stroke
				(width 0.1524)
				(type default)
			)
			(layer "B.SilkS")
		)
		(fp_line
			(start 0.508 -0.9398)
			(end 0.508 0.9398)
			(stroke
				(width 0.1524)
				(type default)
			)
			(layer "B.SilkS")
		)
		(fp_rect
			(start 0.508 0.9398)
			(end -0.508 -0.9398)
			(stroke
				(width 0)
				(type default)
			)
			(fill no)
			(layer "B.CrtYd")
		)
		(fp_rect
			(start 0.508 0.9398)
			(end -0.508 -0.9398)
			(stroke
				(width 0)
				(type default)
			)
			(fill no)
			(layer "B.Fab")
		)
		(pad "1" smd custom
			(at 0 -0.4445 90)
			(size 0.1397 0.1397)
			(layers "B.Cu" "B.Mask" "B.Paste")
			(net "BMC_I2C4_MINI4_SCL_S")
			(options
				(clearance outline)
				(anchor circle)
			)
			(primitives
				(gr_poly
					(pts
						(arc
							(start -0.1778 0.2794)
							(mid -0.249642 0.249642)
							(end -0.2794 0.1778)
						)
						(arc
							(start -0.2794 -0.1778)
							(mid -0.249642 -0.249642)
							(end -0.1778 -0.2794)
						)
						(arc
							(start 0.1778 -0.2794)
							(mid 0.249642 -0.249642)
							(end 0.2794 -0.1778)
						)
						(arc
							(start 0.2794 0.1778)
							(mid 0.249642 0.249642)
							(end 0.1778 0.2794)
						)
					)
					(width 0)
					(fill yes)
				)
			)
		)
		(pad "2" smd custom
			(at 0 0.4445 90)
			(size 0.1397 0.1397)
			(layers "B.Cu" "B.Mask" "B.Paste")
			(net "P3V3_STBY")
			(options
				(clearance outline)
				(anchor circle)
			)
			(primitives
				(gr_poly
					(pts
						(arc
							(start -0.1778 0.2794)
							(mid -0.249642 0.249642)
							(end -0.2794 0.1778)
						)
						(arc
							(start -0.2794 -0.1778)
							(mid -0.249642 -0.249642)
							(end -0.1778 -0.2794)
						)
						(arc
							(start 0.1778 -0.2794)
							(mid 0.249642 -0.249642)
							(end 0.2794 -0.1778)
						)
						(arc
							(start 0.2794 0.1778)
							(mid 0.249642 0.249642)
							(end 0.1778 0.2794)
						)
					)
					(width 0)
					(fill yes)
				)
			)
		)
	)
	(footprint ""
		(layer "B.Cu")
		(at 63.881 -125.5014 -90)
		(property "Reference" "R280"
			(at 0 0 90)
			(layer "B.SilkS")
			(hide yes)
			(effects
				(font
					(size 1.27 1.27)
				)
				(justify mirror)
			)
		)
		(property "Value" "0R2J-2-GP"
			(at -0.064008 -3.993896 270)
			(unlocked yes)
			(layer "B.Fab")
			(hide yes)
			(effects
				(font
					(size 1.016 1.016)
					(thickness 0.1524)
				)
				(justify mirror)
			)
		)
		(property "Device Type" "R402H16"
			(at -0.064008 -5.517896 270)
			(unlocked yes)
			(layer "B.Fab")
			(hide yes)
			(effects
				(font
					(size 1.016 1.016)
					(thickness 0.1524)
				)
				(justify mirror)
			)
		)
		(duplicate_pad_numbers_are_jumpers no)
		(fp_line
			(start -0.508 -0.9398)
			(end 0.508 -0.9398)
			(stroke
				(width 0.1524)
				(type default)
			)
			(layer "B.SilkS")
		)
		(fp_line
			(start 0.508 -0.9398)
			(end 0.508 0.9398)
			(stroke
				(width 0.1524)
				(type default)
			)
			(layer "B.SilkS")
		)
		(fp_rect
			(start 0.508 0.9398)
			(end -0.508 -0.9398)
			(stroke
				(width 0)
				(type default)
			)
			(fill no)
			(layer "B.CrtYd")
		)
		(fp_rect
			(start 0.508 0.9398)
			(end -0.508 -0.9398)
			(stroke
				(width 0)
				(type default)
			)
			(fill no)
			(layer "B.Fab")
		)
		(pad "1" smd custom
			(at 0 -0.4445 90)
			(size 0.1397 0.1397)
			(layers "B.Cu" "B.Mask" "B.Paste")
			(net "BMC_TXD5")
			(options
				(clearance outline)
				(anchor circle)
			)
			(primitives
				(gr_poly
					(pts
						(arc
							(start -0.1778 0.2794)
							(mid -0.249642 0.249642)
							(end -0.2794 0.1778)
						)
						(arc
							(start -0.2794 -0.1778)
							(mid -0.249642 -0.249642)
							(end -0.1778 -0.2794)
						)
						(arc
							(start 0.1778 -0.2794)
							(mid 0.249642 -0.249642)
							(end 0.2794 -0.1778)
						)
						(arc
							(start 0.2794 0.1778)
							(mid 0.249642 0.249642)
							(end 0.1778 0.2794)
						)
					)
					(width 0)
					(fill yes)
				)
			)
		)
		(pad "2" smd custom
			(at 0 0.4445 90)
			(size 0.1397 0.1397)
			(layers "B.Cu" "B.Mask" "B.Paste")
			(net "BMC_TXD5_R")
			(options
				(clearance outline)
				(anchor circle)
			)
			(primitives
				(gr_poly
					(pts
						(arc
							(start -0.1778 0.2794)
							(mid -0.249642 0.249642)
							(end -0.2794 0.1778)
						)
						(arc
							(start -0.2794 -0.1778)
							(mid -0.249642 -0.249642)
							(end -0.1778 -0.2794)
						)
						(arc
							(start 0.1778 -0.2794)
							(mid 0.249642 -0.249642)
							(end 0.2794 -0.1778)
						)
						(arc
							(start 0.2794 0.1778)
							(mid 0.249642 0.249642)
							(end 0.1778 0.2794)
						)
					)
					(width 0)
					(fill yes)
				)
			)
		)
	)
	(footprint ""
		(layer "B.Cu")
		(at 245.1354 -41.995852 -90)
		(property "Reference" "C457"
			(at 0 0 90)
			(layer "B.SilkS")
			(hide yes)
			(effects
				(font
					(size 1.27 1.27)
				)
				(justify mirror)
			)
		)
		(property "Value" "SCD1U16V1KX-1-GP"
			(at 2.8321 -1.7399 270)
			(unlocked yes)
			(layer "B.Fab")
			(hide yes)
			(effects
				(font
					(size 1.016 1.016)
					(thickness 0.1524)
				)
				(justify mirror)
			)
		)
		(property "Device Type" "C0201H13"
			(at 2.8321 -3.2639 270)
			(unlocked yes)
			(layer "B.Fab")
			(hide yes)
			(effects
				(font
					(size 1.016 1.016)
					(thickness 0.1524)
				)
				(justify mirror)
			)
		)
		(duplicate_pad_numbers_are_jumpers no)
		(fp_rect
			(start 0.2794 0.6477)
			(end -0.2794 -0.6477)
			(stroke
				(width 0)
				(type default)
			)
			(fill no)
			(layer "B.CrtYd")
		)
		(fp_rect
			(start 0.2794 0.6477)
			(end -0.2794 -0.6477)
			(stroke
				(width 0)
				(type default)
			)
			(fill no)
			(layer "B.Fab")
		)
		(pad "1" smd custom
			(at 0 -0.2794 90)
			(size 0.0762 0.0762)
			(layers "B.Cu" "B.Mask" "B.Paste")
			(net "DUT_VDD")
			(options
				(clearance outline)
				(anchor circle)
			)
			(primitives
				(gr_poly
					(pts
						(arc
							(start 0.1524 0.127)
							(mid 0.137521 0.162921)
							(end 0.1016 0.1778)
						)
						(arc
							(start -0.1016 0.1778)
							(mid -0.137521 0.162921)
							(end -0.1524 0.127)
						)
						(arc
							(start -0.1524 -0.127)
							(mid -0.137521 -0.162921)
							(end -0.1016 -0.1778)
						)
						(arc
							(start 0.1016 -0.1778)
							(mid 0.137521 -0.162921)
							(end 0.1524 -0.127)
						)
					)
					(width 0)
					(fill yes)
				)
			)
		)
		(pad "2" smd custom
			(at 0 0.2794 90)
			(size 0.0762 0.0762)
			(layers "B.Cu" "B.Mask" "B.Paste")
			(net "GND")
			(options
				(clearance outline)
				(anchor circle)
			)
			(primitives
				(gr_poly
					(pts
						(arc
							(start 0.1524 0.127)
							(mid 0.137521 0.162921)
							(end 0.1016 0.1778)
						)
						(arc
							(start -0.1016 0.1778)
							(mid -0.137521 0.162921)
							(end -0.1524 0.127)
						)
						(arc
							(start -0.1524 -0.127)
							(mid -0.137521 -0.162921)
							(end -0.1016 -0.1778)
						)
						(arc
							(start 0.1016 -0.1778)
							(mid 0.137521 -0.162921)
							(end 0.1524 -0.127)
						)
					)
					(width 0)
					(fill yes)
				)
			)
		)
	)
	(footprint ""
		(layer "B.Cu")
		(at 149.444202 -56.542432)
		(property "Reference" "PR3"
			(at 0 0 0)
			(layer "B.SilkS")
			(hide yes)
			(effects
				(font
					(size 1.27 1.27)
				)
				(justify mirror)
			)
		)
		(property "Value" "82KR2J-GP"
			(at -0.064008 -3.993896 0)
			(unlocked yes)
			(layer "B.Fab")
			(hide yes)
			(effects
				(font
					(size 1.016 1.016)
					(thickness 0.1524)
				)
				(justify mirror)
			)
		)
		(property "Device Type" "R402H16"
			(at -0.064008 -5.517896 0)
			(unlocked yes)
			(layer "B.Fab")
			(hide yes)
			(effects
				(font
					(size 1.016 1.016)
					(thickness 0.1524)
				)
				(justify mirror)
			)
		)
		(duplicate_pad_numbers_are_jumpers no)
		(fp_line
			(start -0.508 -0.9398)
			(end 0.508 -0.9398)
			(stroke
				(width 0.1524)
				(type default)
			)
			(layer "B.SilkS")
		)
		(fp_line
			(start 0.508 -0.9398)
			(end 0.508 0.9398)
			(stroke
				(width 0.1524)
				(type default)
			)
			(layer "B.SilkS")
		)
		(fp_rect
			(start 0.508 0.9398)
			(end -0.508 -0.9398)
			(stroke
				(width 0)
				(type default)
			)
			(fill no)
			(layer "B.CrtYd")
		)
		(fp_rect
			(start 0.508 0.9398)
			(end -0.508 -0.9398)
			(stroke
				(width 0)
				(type default)
			)
			(fill no)
			(layer "B.Fab")
		)
		(pad "1" smd custom
			(at 0 -0.4445 180)
			(size 0.1397 0.1397)
			(layers "B.Cu" "B.Mask" "B.Paste")
			(net "P0V9_TRIP")
			(options
				(clearance outline)
				(anchor circle)
			)
			(primitives
				(gr_poly
					(pts
						(arc
							(start -0.1778 0.2794)
							(mid -0.249642 0.249642)
							(end -0.2794 0.1778)
						)
						(arc
							(start -0.2794 -0.1778)
							(mid -0.249642 -0.249642)
							(end -0.1778 -0.2794)
						)
						(arc
							(start 0.1778 -0.2794)
							(mid 0.249642 -0.249642)
							(end 0.2794 -0.1778)
						)
						(arc
							(start 0.2794 0.1778)
							(mid 0.249642 0.249642)
							(end 0.1778 0.2794)
						)
					)
					(width 0)
					(fill yes)
				)
			)
		)
		(pad "2" smd custom
			(at 0 0.4445 180)
			(size 0.1397 0.1397)
			(layers "B.Cu" "B.Mask" "B.Paste")
			(net "AGND_P0V9")
			(options
				(clearance outline)
				(anchor circle)
			)
			(primitives
				(gr_poly
					(pts
						(arc
							(start -0.1778 0.2794)
							(mid -0.249642 0.249642)
							(end -0.2794 0.1778)
						)
						(arc
							(start -0.2794 -0.1778)
							(mid -0.249642 -0.249642)
							(end -0.1778 -0.2794)
						)
						(arc
							(start 0.1778 -0.2794)
							(mid 0.249642 -0.249642)
							(end 0.2794 -0.1778)
						)
						(arc
							(start 0.2794 0.1778)
							(mid 0.249642 0.249642)
							(end 0.1778 0.2794)
						)
					)
					(width 0)
					(fill yes)
				)
			)
		)
	)
	(footprint ""
		(layer "B.Cu")
		(at 163.998402 -60.073032)
		(property "Reference" "PC208"
			(at 0 0 0)
			(layer "B.SilkS")
			(hide yes)
			(effects
				(font
					(size 1.27 1.27)
				)
				(justify mirror)
			)
		)
		(property "Value" "SCD1U16V2KX-3GP"
			(at -1.1811 -2.7051 0)
			(unlocked yes)
			(layer "B.Fab")
			(hide yes)
			(effects
				(font
					(size 1.016 1.016)
					(thickness 0.1524)
				)
				(justify mirror)
			)
		)
		(property "Device Type" "C402H22"
			(at -1.1811 -4.2291 0)
			(unlocked yes)
			(layer "B.Fab")
			(hide yes)
			(effects
				(font
					(size 1.016 1.016)
					(thickness 0.1524)
				)
				(justify mirror)
			)
		)
		(duplicate_pad_numbers_are_jumpers no)
		(fp_rect
			(start 0.4318 0.9525)
			(end -0.4318 -0.9525)
			(stroke
				(width 0)
				(type default)
			)
			(fill no)
			(layer "B.CrtYd")
		)
		(fp_rect
			(start 0.4318 0.9525)
			(end -0.4318 -0.9525)
			(stroke
				(width 0)
				(type default)
			)
			(fill no)
			(layer "B.Fab")
		)
		(pad "1" smd custom
			(at 0 -0.4445 180)
			(size 0.1524 0.1524)
			(layers "B.Cu" "B.Mask" "B.Paste")
			(net "P0V9")
			(options
				(clearance outline)
				(anchor circle)
			)
			(primitives
				(gr_poly
					(pts
						(arc
							(start 0.3048 0.2032)
							(mid 0.275042 0.275042)
							(end 0.2032 0.3048)
						)
						(arc
							(start -0.2032 0.3048)
							(mid -0.275042 0.275042)
							(end -0.3048 0.2032)
						)
						(arc
							(start -0.3048 -0.2032)
							(mid -0.275042 -0.275042)
							(end -0.2032 -0.3048)
						)
						(arc
							(start 0.2032 -0.3048)
							(mid 0.275042 -0.275042)
							(end 0.3048 -0.2032)
						)
					)
					(width 0)
					(fill yes)
				)
			)
		)
		(pad "2" smd custom
			(at 0 0.4445 180)
			(size 0.1524 0.1524)
			(layers "B.Cu" "B.Mask" "B.Paste")
			(net "P0V9_SW_R")
			(options
				(clearance outline)
				(anchor circle)
			)
			(primitives
				(gr_poly
					(pts
						(arc
							(start 0.3048 0.2032)
							(mid 0.275042 0.275042)
							(end 0.2032 0.3048)
						)
						(arc
							(start -0.2032 0.3048)
							(mid -0.275042 0.275042)
							(end -0.3048 0.2032)
						)
						(arc
							(start -0.3048 -0.2032)
							(mid -0.275042 -0.275042)
							(end -0.2032 -0.3048)
						)
						(arc
							(start 0.2032 -0.3048)
							(mid 0.275042 -0.275042)
							(end 0.3048 -0.2032)
						)
					)
					(width 0)
					(fill yes)
				)
			)
		)
	)
	(footprint ""
		(layer "B.Cu")
		(at 142.374874 -92.22232)
		(property "Reference" "PC89"
			(at 0 0 0)
			(layer "B.SilkS")
			(hide yes)
			(effects
				(font
					(size 1.27 1.27)
				)
				(justify mirror)
			)
		)
		(property "Value" "SC1KP50V2KX-1GP"
			(at -1.1811 -2.7051 0)
			(unlocked yes)
			(layer "B.Fab")
			(hide yes)
			(effects
				(font
					(size 1.016 1.016)
					(thickness 0.1524)
				)
				(justify mirror)
			)
		)
		(property "Device Type" "C402H22"
			(at -1.1811 -4.2291 0)
			(unlocked yes)
			(layer "B.Fab")
			(hide yes)
			(effects
				(font
					(size 1.016 1.016)
					(thickness 0.1524)
				)
				(justify mirror)
			)
		)
		(duplicate_pad_numbers_are_jumpers no)
		(fp_rect
			(start 0.4318 0.9525)
			(end -0.4318 -0.9525)
			(stroke
				(width 0)
				(type default)
			)
			(fill no)
			(layer "B.CrtYd")
		)
		(fp_rect
			(start 0.4318 0.9525)
			(end -0.4318 -0.9525)
			(stroke
				(width 0)
				(type default)
			)
			(fill no)
			(layer "B.Fab")
		)
		(pad "1" smd custom
			(at 0 -0.4445 180)
			(size 0.1524 0.1524)
			(layers "B.Cu" "B.Mask" "B.Paste")
			(net "PWRGD_P1V8_STBY")
			(options
				(clearance outline)
				(anchor circle)
			)
			(primitives
				(gr_poly
					(pts
						(arc
							(start 0.3048 0.2032)
							(mid 0.275042 0.275042)
							(end 0.2032 0.3048)
						)
						(arc
							(start -0.2032 0.3048)
							(mid -0.275042 0.275042)
							(end -0.3048 0.2032)
						)
						(arc
							(start -0.3048 -0.2032)
							(mid -0.275042 -0.275042)
							(end -0.2032 -0.3048)
						)
						(arc
							(start 0.2032 -0.3048)
							(mid 0.275042 -0.275042)
							(end 0.3048 -0.2032)
						)
					)
					(width 0)
					(fill yes)
				)
			)
		)
		(pad "2" smd custom
			(at 0 0.4445 180)
			(size 0.1524 0.1524)
			(layers "B.Cu" "B.Mask" "B.Paste")
			(net "GND")
			(options
				(clearance outline)
				(anchor circle)
			)
			(primitives
				(gr_poly
					(pts
						(arc
							(start 0.3048 0.2032)
							(mid 0.275042 0.275042)
							(end 0.2032 0.3048)
						)
						(arc
							(start -0.2032 0.3048)
							(mid -0.275042 0.275042)
							(end -0.3048 0.2032)
						)
						(arc
							(start -0.3048 -0.2032)
							(mid -0.275042 -0.275042)
							(end -0.2032 -0.3048)
						)
						(arc
							(start 0.2032 -0.3048)
							(mid 0.275042 -0.275042)
							(end 0.3048 -0.2032)
						)
					)
					(width 0)
					(fill yes)
				)
			)
		)
	)
	(footprint ""
		(layer "B.Cu")
		(at 229.108 -23.241 180)
		(property "Reference" "R826"
			(at 0 0 0)
			(layer "B.SilkS")
			(hide yes)
			(effects
				(font
					(size 1.27 1.27)
				)
				(justify mirror)
			)
		)
		(property "Value" "0R2J-2-GP"
			(at -0.064008 -3.993896 180)
			(unlocked yes)
			(layer "B.Fab")
			(hide yes)
			(effects
				(font
					(size 1.016 1.016)
					(thickness 0.1524)
				)
				(justify mirror)
			)
		)
		(property "Device Type" "R402H16"
			(at -0.064008 -5.517896 180)
			(unlocked yes)
			(layer "B.Fab")
			(hide yes)
			(effects
				(font
					(size 1.016 1.016)
					(thickness 0.1524)
				)
				(justify mirror)
			)
		)
		(duplicate_pad_numbers_are_jumpers no)
		(fp_line
			(start 0.508 -0.9398)
			(end 0.508 0.9398)
			(stroke
				(width 0.1524)
				(type default)
			)
			(layer "B.SilkS")
		)
		(fp_line
			(start -0.508 -0.9398)
			(end 0.508 -0.9398)
			(stroke
				(width 0.1524)
				(type default)
			)
			(layer "B.SilkS")
		)
		(fp_rect
			(start 0.508 0.9398)
			(end -0.508 -0.9398)
			(stroke
				(width 0)
				(type default)
			)
			(fill no)
			(layer "B.CrtYd")
		)
		(fp_rect
			(start 0.508 0.9398)
			(end -0.508 -0.9398)
			(stroke
				(width 0)
				(type default)
			)
			(fill no)
			(layer "B.Fab")
		)
		(pad "1" smd custom
			(at 0 -0.4445)
			(size 0.1397 0.1397)
			(layers "B.Cu" "B.Mask" "B.Paste")
			(net "HOST2_RST_N_LS")
			(options
				(clearance outline)
				(anchor circle)
			)
			(primitives
				(gr_poly
					(pts
						(arc
							(start -0.1778 0.2794)
							(mid -0.249642 0.249642)
							(end -0.2794 0.1778)
						)
						(arc
							(start -0.2794 -0.1778)
							(mid -0.249642 -0.249642)
							(end -0.1778 -0.2794)
						)
						(arc
							(start 0.1778 -0.2794)
							(mid 0.249642 -0.249642)
							(end 0.2794 -0.1778)
						)
						(arc
							(start 0.2794 0.1778)
							(mid 0.249642 0.249642)
							(end 0.1778 0.2794)
						)
					)
					(width 0)
					(fill yes)
				)
			)
		)
		(pad "2" smd custom
			(at 0 0.4445)
			(size 0.1397 0.1397)
			(layers "B.Cu" "B.Mask" "B.Paste")
			(net "LBI_ADDR_1_R")
			(options
				(clearance outline)
				(anchor circle)
			)
			(primitives
				(gr_poly
					(pts
						(arc
							(start -0.1778 0.2794)
							(mid -0.249642 0.249642)
							(end -0.2794 0.1778)
						)
						(arc
							(start -0.2794 -0.1778)
							(mid -0.249642 -0.249642)
							(end -0.1778 -0.2794)
						)
						(arc
							(start 0.1778 -0.2794)
							(mid 0.249642 -0.249642)
							(end 0.2794 -0.1778)
						)
						(arc
							(start 0.2794 0.1778)
							(mid 0.249642 0.249642)
							(end 0.1778 0.2794)
						)
					)
					(width 0)
					(fill yes)
				)
			)
		)
	)
)
